# TIMECARD (Time Appliance Project (Time Card)) — schematic netlist excerpt (pin names and nets, part order shuffled) for the footprints in the layout excerpt that follows; sources: Cadence DE-HDL packaged netlist, KiCad conversion of R4006-B0001-02_R01.brd

TP204  TP_PIONT  pkg TP010CT020B030_PTH  page 25 : \1\ = IO_L24N_35
C311  CAPACITOR  18PF 5%  pkg SMC_0201R  page 23 : \1\ = SG ; \2\ = UNNAMED_12_CAPACITOR_I321_2

(kicad_pcb
	(version 20260206)
	(generator "pcbnew")
	(generator_version "10.0")
	(general
		(thickness 1.6)
		(legacy_teardrops no)
	)
	(paper "A4")
	(title_block
		(title "timecard-production-celestica-r4006 — R4006-B0001-02_R01.brd")
		(comment 1 "Time Appliance Project (Time Card) / footprints 591-593 of 1113")
	)
	(layers
		(0 "F.Cu" signal "TOP")
		(4 "In1.Cu" signal "L02_GND1")
		(6 "In2.Cu" signal "L03_SIG1")
		(8 "In3.Cu" signal "L04_GND2")
		(10 "In4.Cu" signal "L05_VCC1")
		(12 "In5.Cu" signal "L06_VCC2")
		(14 "In6.Cu" signal "L07_GND3")
		(16 "In7.Cu" signal "L08_SIG2")
		(18 "In8.Cu" signal "L09_GND4")
		(2 "B.Cu" signal "BOTTOM")
		(9 "F.Adhes" user "F.Adhesive")
		(11 "B.Adhes" user "B.Adhesive")
		(13 "F.Paste" user "Package Geometry/Pastemask Top")
		(15 "B.Paste" user "Package Geometry/Pastemask Bottom")
		(5 "F.SilkS" user "Ref Des/Silkscreen Top")
		(7 "B.SilkS" user "Ref Des/Silkscreen Bottom")
		(1 "F.Mask" user "Board Geometry/Soldermask Top")
		(3 "B.Mask" user "Board Geometry/Soldermask Bottom")
		(17 "Dwgs.User" user "User.Drawings")
		(19 "Cmts.User" user "User.Comments")
		(21 "Eco1.User" user "User.Eco1")
		(23 "Eco2.User" user "User.Eco2")
		(25 "Edge.Cuts" user "Board Geometry/Outline")
		(27 "Margin" user)
		(31 "F.CrtYd" user "Package Geometry/Place Bound Top")
		(29 "B.CrtYd" user "Package Geometry/Place Bound Bottom")
		(35 "F.Fab" user "Ref Des/Assembly Top")
		(33 "B.Fab" user "Ref Des/Assembly Bottom")
	)
	(footprint ""
		(layer "F.Cu")
		(at 13.0556 -25.4)
		(property "Reference" "C311"
			(at -2.6416 0.03937 0)
			(unlocked yes)
			(layer "F.SilkS")
			(effects
				(font
					(size 0.7874 0.5842)
					(thickness 0.1524)
				)
			)
		)
		(property "Value" "VAL*"
			(at 0.193548 2.13614 0)
			(unlocked yes)
			(layer "F.Fab")
			(hide yes)
			(effects
				(font
					(size 0.7874 0.5842)
					(thickness 0.1524)
				)
			)
		)
		(property "User Part Number" "PARTNUM*"
			(at 0.216154 4.185666 0)
			(unlocked yes)
			(layer "Cmts.User")
			(hide yes)
			(effects
				(font
					(size 0.7874 0.5842)
					(thickness 0.1524)
				)
			)
		)
		(property "Device Type" "CAPACITOR-G104-0A180-FJ,18PF,5%"
			(at 0.184404 1.180592 0)
			(unlocked yes)
			(layer "F.Fab")
			(hide yes)
			(effects
				(font
					(size 0.7874 0.5842)
					(thickness 0.1524)
				)
			)
		)
		(property "Tolerance" "TOL*"
			(at 0.216154 3.1496 0)
			(unlocked yes)
			(layer "Cmts.User")
			(hide yes)
			(effects
				(font
					(size 0.7874 0.5842)
					(thickness 0.1524)
				)
			)
		)
		(duplicate_pad_numbers_are_jumpers no)
		(fp_line
			(start -0.671322 -0.4445)
			(end 0.671322 -0.4445)
			(stroke
				(width 0.1)
				(type default)
			)
			(layer "F.SilkS")
		)
		(fp_line
			(start -0.671322 0.4445)
			(end -0.671322 -0.4445)
			(stroke
				(width 0.1)
				(type default)
			)
			(layer "F.SilkS")
		)
		(fp_line
			(start 0.671322 -0.4445)
			(end 0.671322 0.4445)
			(stroke
				(width 0.1)
				(type default)
			)
			(layer "F.SilkS")
		)
		(fp_line
			(start 0.671322 0.4445)
			(end -0.671322 0.4445)
			(stroke
				(width 0.1)
				(type default)
			)
			(layer "F.SilkS")
		)
		(fp_rect
			(start -0.671322 0.4445)
			(end 0.671322 -0.4445)
			(stroke
				(width 0)
				(type default)
			)
			(fill no)
			(layer "F.CrtYd")
		)
		(fp_line
			(start -0.31496 -0.1651)
			(end -0.31496 0.1651)
			(stroke
				(width 0.1)
				(type default)
			)
			(layer "F.Fab")
		)
		(fp_line
			(start -0.31496 0.1651)
			(end 0.31496 0.1651)
			(stroke
				(width 0.1)
				(type default)
			)
			(layer "F.Fab")
		)
		(fp_line
			(start 0.31496 -0.1651)
			(end -0.31496 -0.1651)
			(stroke
				(width 0.1)
				(type default)
			)
			(layer "F.Fab")
		)
		(fp_line
			(start 0.31496 0.1651)
			(end 0.31496 -0.1651)
			(stroke
				(width 0.1)
				(type default)
			)
			(layer "F.Fab")
		)
		(pad "1" smd rect
			(at -0.264922 0)
			(size 0.3048 0.381)
			(layers "F.Cu" "F.Mask" "F.Paste")
			(net "SG")
		)
		(pad "2" smd rect
			(at 0.264922 0)
			(size 0.3048 0.381)
			(layers "F.Cu" "F.Mask" "F.Paste")
			(net "UNNAMED_12_CAPACITOR_I321_2")
		)
		(zone
			(layer "F.Cu")
			(hatch none 0.5)
			(connect_pads
				(clearance 0)
			)
			(min_thickness 0.25)
			(keepout
				(tracks allowed)
				(vias not_allowed)
				(pads allowed)
				(copperpour not_allowed)
				(footprints allowed)
			)
			(placement
				(enabled no)
				(sheetname "")
			)
			(fill
				(thermal_gap 0.5)
				(thermal_bridge_width 0.5)
				(island_removal_mode 0)
			)
			(polygon
				(pts
					(xy 12.943078 -25.5905) (xy 12.943078 -25.2095) (xy 13.168122 -25.2095) (xy 13.168122 -25.5905)
				)
			)
		)
		(zone
			(layer "F.Cu")
			(hatch none 0.5)
			(connect_pads
				(clearance 0)
			)
			(min_thickness 0.25)
			(keepout
				(tracks not_allowed)
				(vias allowed)
				(pads allowed)
				(copperpour not_allowed)
				(footprints allowed)
			)
			(placement
				(enabled no)
				(sheetname "")
			)
			(fill
				(thermal_gap 0.5)
				(thermal_bridge_width 0.5)
				(island_removal_mode 0)
			)
			(polygon
				(pts
					(xy 12.943078 -25.2095) (xy 13.168122 -25.2095) (xy 13.168122 -25.5905) (xy 12.943078 -25.5905)
				)
			)
		)
	)
	(footprint ""
		(layer "F.Cu")
		(at 36.83 -125.603)
		(property "Reference" "SP75"
			(at 0 0 0)
			(layer "F.SilkS")
			(hide yes)
			(effects
				(font
					(size 1.27 1.27)
				)
			)
		)
		(property "Value" ""
			(at 0 0 0)
			(layer "F.Fab")
			(effects
				(font
					(size 1.27 1.27)
				)
			)
		)
		(duplicate_pad_numbers_are_jumpers no)
	)
	(footprint ""
		(layer "F.Cu")
		(at 108.966 -31.369 90)
		(property "Reference" "TP204"
			(at -1.17475 -0.6858 0)
			(unlocked yes)
			(layer "F.SilkS")
			(effects
				(font
					(size 0.635 0.4064)
					(thickness 0.1524)
				)
				(justify left)
			)
		)
		(property "Value" ""
			(at 0 0 90)
			(layer "F.Fab")
			(effects
				(font
					(size 1.27 1.27)
				)
			)
		)
		(property "Device Type" "TP_PIONT-TP010CT020B030_PTH-TPA"
			(at -1.341882 0.996696 90)
			(unlocked yes)
			(layer "F.Fab")
			(hide yes)
			(effects
				(font
					(size 0.7874 0.5842)
					(thickness 0.1524)
				)
				(justify left)
			)
		)
		(duplicate_pad_numbers_are_jumpers no)
		(fp_poly
			(pts
				(arc
					(start 0 0.889)
					(mid 0 -0.889)
					(end 0 0.889)
				)
			)
			(stroke
				(width 0)
				(type default)
			)
			(fill no)
			(layer "B.CrtYd")
		)
		(fp_poly
			(pts
				(arc
					(start 0 0.889)
					(mid 0 -0.889)
					(end 0 0.889)
				)
			)
			(stroke
				(width 0)
				(type default)
			)
			(fill no)
			(layer "F.CrtYd")
		)
		(pad "1" thru_hole circle
			(at 0 0 90)
			(size 0.508 0.508)
			(drill 0.254)
			(layers "*.Cu" "*.Mask")
			(remove_unused_layers no)
			(net "IO_L24N_35")
			(clearance 0.1016)
			(padstack
				(mode front_inner_back)
				(layer "Inner"
					(shape circle)
					(size 0.508 0.508)
					(clearance 0.1016)
				)
				(layer "B.Cu"
					(shape circle)
					(size 0.762 0.762)
					(clearance -0.0254)
				)
			)
		)
	)
)
